(kicad_pcb
	(version 20241229)
	(generator "pcbnew")
	(generator_version "9.0")
	(general
		(thickness 1.599998)
		(legacy_teardrops no)
	)
	(paper "A4")
	(title_block
		(date "2023-02-12")
		(rev "1.1.5")
		(comment 9 "footprints 358-363 of 473")
	)
	(layers
		(0 "F.Cu" signal)
		(4 "In1.Cu" power "In1.GND")
		(6 "In2.Cu" signal)
		(8 "In3.Cu" power "In3.GND")
		(10 "In4.Cu" power "In4.VCC")
		(12 "In5.Cu" signal)
		(14 "In6.Cu" power "In6.VCC")
		(2 "B.Cu" signal)
		(9 "F.Adhes" user "F.Adhesive")
		(11 "B.Adhes" user "B.Adhesive")
		(13 "F.Paste" user)
		(15 "B.Paste" user)
		(5 "F.SilkS" user "F.Silkscreen")
		(7 "B.SilkS" user "B.Silkscreen")
		(1 "F.Mask" user)
		(3 "B.Mask" user)
		(17 "Dwgs.User" user "User.Drawings")
		(19 "Cmts.User" user "User.Comments")
		(21 "Eco1.User" user "User.Eco1")
		(23 "Eco2.User" user "User.Eco2")
		(25 "Edge.Cuts" user)
		(27 "Margin" user)
		(31 "F.CrtYd" user "F.Courtyard")
		(29 "B.CrtYd" user "B.Courtyard")
		(35 "F.Fab" user)
		(33 "B.Fab" user)
	)
	(footprint "antmicro-footprints:C_0201"
		(layer "B.Cu")
		(at 168.25 87.625 90)
		(descr "Capacitor SMD 0201")
		(tags "capacitor SMD 0201")
		(property "Reference" "C39"
			(at 2.725 0.45 270)
			(layer "B.SilkS")
			(effects
				(font
					(size 0.7 0.7)
					(thickness 0.15)
				)
				(justify left bottom mirror)
			)
		)
		(property "Value" "C_100n_0201"
			(at 0 -1.4 270)
			(layer "B.Fab")
			(effects
				(font
					(size 0.7 0.7)
					(thickness 0.15)
				)
				(justify left bottom mirror)
			)
		)
		(property "Description" " "
			(at 0 0 90)
			(layer "F.Fab")
			(hide yes)
			(effects
				(font
					(size 1.27 1.27)
					(thickness 0.15)
				)
			)
		)
		(property "Author" "Antmicro"
			(at 255.875 -80.625 0)
			(layer "B.Fab")
			(hide yes)
			(effects
				(font
					(size 1 1)
					(thickness 0.15)
				)
				(justify mirror)
			)
		)
		(property "Dielectric" ""
			(at 255.875 -80.625 0)
			(layer "B.Fab")
			(hide yes)
			(effects
				(font
					(size 1 1)
					(thickness 0.15)
				)
				(justify mirror)
			)
		)
		(property "License" "Apache-2.0"
			(at 255.875 -80.625 0)
			(layer "B.Fab")
			(hide yes)
			(effects
				(font
					(size 1 1)
					(thickness 0.15)
				)
				(justify mirror)
			)
		)
		(property "MPN" "CC0201KRX6S5BB104"
			(at 255.875 -80.625 0)
			(layer "B.Fab")
			(hide yes)
			(effects
				(font
					(size 1 1)
					(thickness 0.15)
				)
				(justify mirror)
			)
		)
		(property "Manufacturer" "Yaego"
			(at 255.875 -80.625 0)
			(layer "B.Fab")
			(hide yes)
			(effects
				(font
					(size 1 1)
					(thickness 0.15)
				)
				(justify mirror)
			)
		)
		(property "Val" "100n"
			(at 255.875 -80.625 0)
			(layer "B.Fab")
			(hide yes)
			(effects
				(font
					(size 1 1)
					(thickness 0.15)
				)
				(justify mirror)
			)
		)
		(property "Voltage" ""
			(at 255.875 -80.625 0)
			(layer "B.Fab")
			(hide yes)
			(effects
				(font
					(size 1 1)
					(thickness 0.15)
				)
				(justify mirror)
			)
		)
		(sheetname "FPGA power")
		(sheetfile "fpga-power.kicad_sch")
		(attr smd)
		(fp_rect
			(start -0.72 0.38)
			(end 0.72 -0.38)
			(stroke
				(width 0.05)
				(type solid)
			)
			(fill no)
			(layer "B.CrtYd")
		)
		(fp_rect
			(start 0.3 -0.15)
			(end -0.301 0.149)
			(stroke
				(width 0.15)
				(type solid)
			)
			(fill no)
			(layer "B.Fab")
		)
		(pad "" smd roundrect
			(at -0.349 0.002 90)
			(size 0.318 0.36)
			(layers "B.Paste")
			(roundrect_rratio 0.25)
		)
		(pad "" smd roundrect
			(at 0.341 0.002 90)
			(size 0.318 0.36)
			(layers "B.Paste")
			(roundrect_rratio 0.25)
		)
		(pad "1" smd roundrect
			(at -0.321 0.002 90)
			(size 0.46 0.4)
			(layers "B.Cu" "B.Mask")
			(roundrect_rratio 0.25)
			(net 66 "VDDQ")
			(pintype "passive")
		)
		(pad "2" smd roundrect
			(at 0.32 0.002 90)
			(size 0.46 0.4)
			(layers "B.Cu" "B.Mask")
			(roundrect_rratio 0.25)
			(net 5 "GND")
			(pintype "passive")
		)
	)
	(footprint "antmicro-footprints:C_0201"
		(layer "B.Cu")
		(at 161.136328 87.597157 180)
		(descr "Capacitor SMD 0201")
		(tags "capacitor SMD 0201")
		(property "Reference" "C43"
			(at -1.263672 0.397157 0)
			(layer "B.SilkS")
			(effects
				(font
					(size 0.7 0.7)
					(thickness 0.15)
				)
				(justify left bottom mirror)
			)
		)
		(property "Value" "C_100n_0201"
			(at 0 -1.4 0)
			(layer "B.Fab")
			(effects
				(font
					(size 0.7 0.7)
					(thickness 0.15)
				)
				(justify left bottom mirror)
			)
		)
		(property "Description" " "
			(at 0 0 180)
			(layer "F.Fab")
			(hide yes)
			(effects
				(font
					(size 1.27 1.27)
					(thickness 0.15)
				)
			)
		)
		(property "Author" "Antmicro"
			(at 322.272656 175.194314 0)
			(layer "B.Fab")
			(hide yes)
			(effects
				(font
					(size 1 1)
					(thickness 0.15)
				)
				(justify mirror)
			)
		)
		(property "Dielectric" ""
			(at 322.272656 175.194314 0)
			(layer "B.Fab")
			(hide yes)
			(effects
				(font
					(size 1 1)
					(thickness 0.15)
				)
				(justify mirror)
			)
		)
		(property "License" "Apache-2.0"
			(at 322.272656 175.194314 0)
			(layer "B.Fab")
			(hide yes)
			(effects
				(font
					(size 1 1)
					(thickness 0.15)
				)
				(justify mirror)
			)
		)
		(property "MPN" "CC0201KRX6S5BB104"
			(at 322.272656 175.194314 0)
			(layer "B.Fab")
			(hide yes)
			(effects
				(font
					(size 1 1)
					(thickness 0.15)
				)
				(justify mirror)
			)
		)
		(property "Manufacturer" "Yaego"
			(at 322.272656 175.194314 0)
			(layer "B.Fab")
			(hide yes)
			(effects
				(font
					(size 1 1)
					(thickness 0.15)
				)
				(justify mirror)
			)
		)
		(property "Val" "100n"
			(at 322.272656 175.194314 0)
			(layer "B.Fab")
			(hide yes)
			(effects
				(font
					(size 1 1)
					(thickness 0.15)
				)
				(justify mirror)
			)
		)
		(property "Voltage" ""
			(at 322.272656 175.194314 0)
			(layer "B.Fab")
			(hide yes)
			(effects
				(font
					(size 1 1)
					(thickness 0.15)
				)
				(justify mirror)
			)
		)
		(sheetname "FPGA power")
		(sheetfile "fpga-power.kicad_sch")
		(attr smd)
		(fp_rect
			(start -0.72 0.38)
			(end 0.72 -0.38)
			(stroke
				(width 0.05)
				(type solid)
			)
			(fill no)
			(layer "B.CrtYd")
		)
		(fp_rect
			(start 0.3 -0.15)
			(end -0.301 0.149)
			(stroke
				(width 0.15)
				(type solid)
			)
			(fill no)
			(layer "B.Fab")
		)
		(pad "" smd roundrect
			(at -0.349 0.002 180)
			(size 0.318 0.36)
			(layers "B.Paste")
			(roundrect_rratio 0.25)
		)
		(pad "" smd roundrect
			(at 0.341 0.002 180)
			(size 0.318 0.36)
			(layers "B.Paste")
			(roundrect_rratio 0.25)
		)
		(pad "1" smd roundrect
			(at -0.321 0.002 180)
			(size 0.46 0.4)
			(layers "B.Cu" "B.Mask")
			(roundrect_rratio 0.25)
			(net 66 "VDDQ")
			(pintype "passive")
		)
		(pad "2" smd roundrect
			(at 0.32 0.002 180)
			(size 0.46 0.4)
			(layers "B.Cu" "B.Mask")
			(roundrect_rratio 0.25)
			(net 5 "GND")
			(pintype "passive")
		)
	)
	(footprint "antmicro-footprints:C_0201"
		(layer "B.Cu")
		(at 161.25 91.375 -90)
		(descr "Capacitor SMD 0201")
		(tags "capacitor SMD 0201")
		(property "Reference" "C47"
			(at 0.525 -0.35 90)
			(layer "B.SilkS")
			(effects
				(font
					(size 0.7 0.7)
					(thickness 0.15)
				)
				(justify left bottom mirror)
			)
		)
		(property "Value" "C_100n_0201"
			(at 0 -1.4 90)
			(layer "B.Fab")
			(effects
				(font
					(size 0.7 0.7)
					(thickness 0.15)
				)
				(justify left bottom mirror)
			)
		)
		(property "Description" " "
			(at 0 0 270)
			(layer "F.Fab")
			(hide yes)
			(effects
				(font
					(size 1.27 1.27)
					(thickness 0.15)
				)
			)
		)
		(property "Author" "Antmicro"
			(at 69.875 252.625 0)
			(layer "B.Fab")
			(hide yes)
			(effects
				(font
					(size 1 1)
					(thickness 0.15)
				)
				(justify mirror)
			)
		)
		(property "Dielectric" ""
			(at 69.875 252.625 0)
			(layer "B.Fab")
			(hide yes)
			(effects
				(font
					(size 1 1)
					(thickness 0.15)
				)
				(justify mirror)
			)
		)
		(property "License" "Apache-2.0"
			(at 69.875 252.625 0)
			(layer "B.Fab")
			(hide yes)
			(effects
				(font
					(size 1 1)
					(thickness 0.15)
				)
				(justify mirror)
			)
		)
		(property "MPN" "CC0201KRX6S5BB104"
			(at 69.875 252.625 0)
			(layer "B.Fab")
			(hide yes)
			(effects
				(font
					(size 1 1)
					(thickness 0.15)
				)
				(justify mirror)
			)
		)
		(property "Manufacturer" "Yaego"
			(at 69.875 252.625 0)
			(layer "B.Fab")
			(hide yes)
			(effects
				(font
					(size 1 1)
					(thickness 0.15)
				)
				(justify mirror)
			)
		)
		(property "Val" "100n"
			(at 69.875 252.625 0)
			(layer "B.Fab")
			(hide yes)
			(effects
				(font
					(size 1 1)
					(thickness 0.15)
				)
				(justify mirror)
			)
		)
		(property "Voltage" ""
			(at 69.875 252.625 0)
			(layer "B.Fab")
			(hide yes)
			(effects
				(font
					(size 1 1)
					(thickness 0.15)
				)
				(justify mirror)
			)
		)
		(sheetname "FPGA power")
		(sheetfile "fpga-power.kicad_sch")
		(attr smd)
		(fp_rect
			(start -0.72 0.38)
			(end 0.72 -0.38)
			(stroke
				(width 0.05)
				(type solid)
			)
			(fill no)
			(layer "B.CrtYd")
		)
		(fp_rect
			(start 0.3 -0.15)
			(end -0.301 0.149)
			(stroke
				(width 0.15)
				(type solid)
			)
			(fill no)
			(layer "B.Fab")
		)
		(pad "" smd roundrect
			(at -0.349 0.002 270)
			(size 0.318 0.36)
			(layers "B.Paste")
			(roundrect_rratio 0.25)
		)
		(pad "" smd roundrect
			(at 0.341 0.002 270)
			(size 0.318 0.36)
			(layers "B.Paste")
			(roundrect_rratio 0.25)
		)
		(pad "1" smd roundrect
			(at -0.321 0.002 270)
			(size 0.46 0.4)
			(layers "B.Cu" "B.Mask")
			(roundrect_rratio 0.25)
			(net 66 "VDDQ")
			(pintype "passive")
		)
		(pad "2" smd roundrect
			(at 0.32 0.002 270)
			(size 0.46 0.4)
			(layers "B.Cu" "B.Mask")
			(roundrect_rratio 0.25)
			(net 5 "GND")
			(pintype "passive")
		)
	)
	(footprint "antmicro-footprints:C_0201"
		(layer "B.Cu")
		(at 169 91.5)
		(descr "Capacitor SMD 0201")
		(tags "capacitor SMD 0201")
		(property "Reference" "C62"
			(at 2.5 -1.8 180)
			(layer "B.SilkS")
			(effects
				(font
					(size 0.7 0.7)
					(thickness 0.15)
				)
				(justify left bottom mirror)
			)
		)
		(property "Value" "C_100n_0201"
			(at 0 -1.4 180)
			(layer "B.Fab")
			(effects
				(font
					(size 0.7 0.7)
					(thickness 0.15)
				)
				(justify left bottom mirror)
			)
		)
		(property "Description" " "
			(at 0 0 0)
			(layer "F.Fab")
			(hide yes)
			(effects
				(font
					(size 1.27 1.27)
					(thickness 0.15)
				)
			)
		)
		(property "Author" "Antmicro"
			(at 0 0 0)
			(layer "B.Fab")
			(hide yes)
			(effects
				(font
					(size 1 1)
					(thickness 0.15)
				)
				(justify mirror)
			)
		)
		(property "Dielectric" ""
			(at 0 0 0)
			(layer "B.Fab")
			(hide yes)
			(effects
				(font
					(size 1 1)
					(thickness 0.15)
				)
				(justify mirror)
			)
		)
		(property "License" "Apache-2.0"
			(at 0 0 0)
			(layer "B.Fab")
			(hide yes)
			(effects
				(font
					(size 1 1)
					(thickness 0.15)
				)
				(justify mirror)
			)
		)
		(property "MPN" "CC0201KRX6S5BB104"
			(at 0 0 0)
			(layer "B.Fab")
			(hide yes)
			(effects
				(font
					(size 1 1)
					(thickness 0.15)
				)
				(justify mirror)
			)
		)
		(property "Manufacturer" "Yaego"
			(at 0 0 0)
			(layer "B.Fab")
			(hide yes)
			(effects
				(font
					(size 1 1)
					(thickness 0.15)
				)
				(justify mirror)
			)
		)
		(property "Val" "100n"
			(at 0 0 0)
			(layer "B.Fab")
			(hide yes)
			(effects
				(font
					(size 1 1)
					(thickness 0.15)
				)
				(justify mirror)
			)
		)
		(property "Voltage" ""
			(at 0 0 0)
			(layer "B.Fab")
			(hide yes)
			(effects
				(font
					(size 1 1)
					(thickness 0.15)
				)
				(justify mirror)
			)
		)
		(sheetname "FPGA power")
		(sheetfile "fpga-power.kicad_sch")
		(attr smd)
		(fp_rect
			(start -0.72 0.38)
			(end 0.72 -0.38)
			(stroke
				(width 0.05)
				(type solid)
			)
			(fill no)
			(layer "B.CrtYd")
		)
		(fp_rect
			(start 0.3 -0.15)
			(end -0.301 0.149)
			(stroke
				(width 0.15)
				(type solid)
			)
			(fill no)
			(layer "B.Fab")
		)
		(pad "" smd roundrect
			(at -0.349 0.002)
			(size 0.318 0.36)
			(layers "B.Paste")
			(roundrect_rratio 0.25)
		)
		(pad "" smd roundrect
			(at 0.341 0.002)
			(size 0.318 0.36)
			(layers "B.Paste")
			(roundrect_rratio 0.25)
		)
		(pad "1" smd roundrect
			(at -0.321 0.002)
			(size 0.46 0.4)
			(layers "B.Cu" "B.Mask")
			(roundrect_rratio 0.25)
			(net 465 "1V0_SYS")
			(pintype "passive")
		)
		(pad "2" smd roundrect
			(at 0.32 0.002)
			(size 0.46 0.4)
			(layers "B.Cu" "B.Mask")
			(roundrect_rratio 0.25)
			(net 5 "GND")
			(pintype "passive")
		)
	)
	(footprint "antmicro-footprints:C_0201"
		(layer "B.Cu")
		(at 170.375 100.75)
		(descr "Capacitor SMD 0201")
		(tags "capacitor SMD 0201")
		(property "Reference" "C66"
			(at 1.425 1.15 180)
			(layer "B.SilkS")
			(effects
				(font
					(size 0.7 0.7)
					(thickness 0.15)
				)
				(justify left bottom mirror)
			)
		)
		(property "Value" "C_100n_0201"
			(at 0 -1.4 180)
			(layer "B.Fab")
			(effects
				(font
					(size 0.7 0.7)
					(thickness 0.15)
				)
				(justify left bottom mirror)
			)
		)
		(property "Description" " "
			(at 0 0 0)
			(layer "F.Fab")
			(hide yes)
			(effects
				(font
					(size 1.27 1.27)
					(thickness 0.15)
				)
			)
		)
		(property "Author" "Antmicro"
			(at 0 0 0)
			(layer "B.Fab")
			(hide yes)
			(effects
				(font
					(size 1 1)
					(thickness 0.15)
				)
				(justify mirror)
			)
		)
		(property "Dielectric" ""
			(at 0 0 0)
			(layer "B.Fab")
			(hide yes)
			(effects
				(font
					(size 1 1)
					(thickness 0.15)
				)
				(justify mirror)
			)
		)
		(property "License" "Apache-2.0"
			(at 0 0 0)
			(layer "B.Fab")
			(hide yes)
			(effects
				(font
					(size 1 1)
					(thickness 0.15)
				)
				(justify mirror)
			)
		)
		(property "MPN" "CC0201KRX6S5BB104"
			(at 0 0 0)
			(layer "B.Fab")
			(hide yes)
			(effects
				(font
					(size 1 1)
					(thickness 0.15)
				)
				(justify mirror)
			)
		)
		(property "Manufacturer" "Yaego"
			(at 0 0 0)
			(layer "B.Fab")
			(hide yes)
			(effects
				(font
					(size 1 1)
					(thickness 0.15)
				)
				(justify mirror)
			)
		)
		(property "Val" "100n"
			(at 0 0 0)
			(layer "B.Fab")
			(hide yes)
			(effects
				(font
					(size 1 1)
					(thickness 0.15)
				)
				(justify mirror)
			)
		)
		(property "Voltage" ""
			(at 0 0 0)
			(layer "B.Fab")
			(hide yes)
			(effects
				(font
					(size 1 1)
					(thickness 0.15)
				)
				(justify mirror)
			)
		)
		(sheetname "FPGA power")
		(sheetfile "fpga-power.kicad_sch")
		(attr smd)
		(fp_rect
			(start -0.72 0.38)
			(end 0.72 -0.38)
			(stroke
				(width 0.05)
				(type solid)
			)
			(fill no)
			(layer "B.CrtYd")
		)
		(fp_rect
			(start 0.3 -0.15)
			(end -0.301 0.149)
			(stroke
				(width 0.15)
				(type solid)
			)
			(fill no)
			(layer "B.Fab")
		)
		(pad "" smd roundrect
			(at -0.349 0.002)
			(size 0.318 0.36)
			(layers "B.Paste")
			(roundrect_rratio 0.25)
		)
		(pad "" smd roundrect
			(at 0.341 0.002)
			(size 0.318 0.36)
			(layers "B.Paste")
			(roundrect_rratio 0.25)
		)
		(pad "1" smd roundrect
			(at -0.321 0.002)
			(size 0.46 0.4)
			(layers "B.Cu" "B.Mask")
			(roundrect_rratio 0.25)
			(net 465 "1V0_SYS")
			(pintype "passive")
		)
		(pad "2" smd roundrect
			(at 0.32 0.002)
			(size 0.46 0.4)
			(layers "B.Cu" "B.Mask")
			(roundrect_rratio 0.25)
			(net 5 "GND")
			(pintype "passive")
		)
	)
	(footprint "antmicro-footprints:C_0201"
		(layer "B.Cu")
		(at 165.625 87.625)
		(descr "Capacitor SMD 0201")
		(tags "capacitor SMD 0201")
		(property "Reference" "C35"
			(at 1.075 -0.325 180)
			(layer "B.SilkS")
			(effects
				(font
					(size 0.7 0.7)
					(thickness 0.15)
				)
				(justify left bottom mirror)
			)
		)
		(property "Value" "C_100n_0201"
			(at 0 -1.4 180)
			(layer "B.Fab")
			(effects
				(font
					(size 0.7 0.7)
					(thickness 0.15)
				)
				(justify left bottom mirror)
			)
		)
		(property "Description" " "
			(at 0 0 0)
			(layer "F.Fab")
			(hide yes)
			(effects
				(font
					(size 1.27 1.27)
					(thickness 0.15)
				)
			)
		)
		(property "Author" "Antmicro"
			(at 0 0 0)
			(layer "B.Fab")
			(hide yes)
			(effects
				(font
					(size 1 1)
					(thickness 0.15)
				)
				(justify mirror)
			)
		)
		(property "Dielectric" ""
			(at 0 0 0)
			(layer "B.Fab")
			(hide yes)
			(effects
				(font
					(size 1 1)
					(thickness 0.15)
				)
				(justify mirror)
			)
		)
		(property "License" "Apache-2.0"
			(at 0 0 0)
			(layer "B.Fab")
			(hide yes)
			(effects
				(font
					(size 1 1)
					(thickness 0.15)
				)
				(justify mirror)
			)
		)
		(property "MPN" "CC0201KRX6S5BB104"
			(at 0 0 0)
			(layer "B.Fab")
			(hide yes)
			(effects
				(font
					(size 1 1)
					(thickness 0.15)
				)
				(justify mirror)
			)
		)
		(property "Manufacturer" "Yaego"
			(at 0 0 0)
			(layer "B.Fab")
			(hide yes)
			(effects
				(font
					(size 1 1)
					(thickness 0.15)
				)
				(justify mirror)
			)
		)
		(property "Val" "100n"
			(at 0 0 0)
			(layer "B.Fab")
			(hide yes)
			(effects
				(font
					(size 1 1)
					(thickness 0.15)
				)
				(justify mirror)
			)
		)
		(property "Voltage" ""
			(at 0 0 0)
			(layer "B.Fab")
			(hide yes)
			(effects
				(font
					(size 1 1)
					(thickness 0.15)
				)
				(justify mirror)
			)
		)
		(sheetname "FPGA power")
		(sheetfile "fpga-power.kicad_sch")
		(attr smd)
		(fp_rect
			(start -0.72 0.38)
			(end 0.72 -0.38)
			(stroke
				(width 0.05)
				(type solid)
			)
			(fill no)
			(layer "B.CrtYd")
		)
		(fp_rect
			(start 0.3 -0.15)
			(end -0.301 0.149)
			(stroke
				(width 0.15)
				(type solid)
			)
			(fill no)
			(layer "B.Fab")
		)
		(pad "" smd roundrect
			(at -0.349 0.002)
			(size 0.318 0.36)
			(layers "B.Paste")
			(roundrect_rratio 0.25)
		)
		(pad "" smd roundrect
			(at 0.341 0.002)
			(size 0.318 0.36)
			(layers "B.Paste")
			(roundrect_rratio 0.25)
		)
		(pad "1" smd roundrect
			(at -0.321 0.002)
			(size 0.46 0.4)
			(layers "B.Cu" "B.Mask")
			(roundrect_rratio 0.25)
			(net 66 "VDDQ")
			(pintype "passive")
		)
		(pad "2" smd roundrect
			(at 0.32 0.002)
			(size 0.46 0.4)
			(layers "B.Cu" "B.Mask")
			(roundrect_rratio 0.25)
			(net 5 "GND")
			(pintype "passive")
		)
	)
)
